# BASEBOARD_FAB2 (Tioga Pass) — schematic netlist excerpt (pin names and nets, part order shuffled) for the footprints in the layout excerpt that follows; sources: Cadence DE-HDL packaged netlist, KiCad conversion of Wiwynn_Tioga_Pass_MB.brd

C25W98  CAP  1.0UF 16V 10% X6S  pkg 0402  page 255 : A = P3V3_STBY ; B = GND
C5G63  CAP_A  22.0UF 4V 20% X6S  pkg 0603V  page 242 : A = PVDDQ_DEF ; B = GND
R9F26  RES  0.0 5% EMPTY  pkg 0402  page 158 : A = SP2_BMC_CM_UART_TX ; B = SPA_MID_DBG_TX

(kicad_pcb
	(version 20260206)
	(generator "pcbnew")
	(generator_version "10.0")
	(general
		(thickness 1.6)
		(legacy_teardrops no)
	)
	(paper "A4")
	(title_block
		(title "Wiwynn_Tioga_Pass_MB.brd")
		(comment 1 "Tioga Pass / footprints 2700-2702 of 4770")
	)
	(layers
		(0 "F.Cu" signal "TOP")
		(4 "In1.Cu" signal "L2GND")
		(6 "In2.Cu" signal "L3")
		(8 "In3.Cu" signal "L4GND")
		(10 "In4.Cu" signal "L5")
		(12 "In5.Cu" signal "L6GND")
		(14 "In6.Cu" signal "L7VCC")
		(16 "In7.Cu" signal "L8VCC")
		(18 "In8.Cu" signal "L9GND")
		(20 "In9.Cu" signal "L10")
		(22 "In10.Cu" signal "L11GND")
		(24 "In11.Cu" signal "L12")
		(26 "In12.Cu" signal "L13GND")
		(2 "B.Cu" signal "BOTTOM")
		(9 "F.Adhes" user "F.Adhesive")
		(11 "B.Adhes" user "B.Adhesive")
		(13 "F.Paste" user "Package Geometry/Pastemask Top")
		(15 "B.Paste" user "Package Geometry/Pastemask Bottom")
		(5 "F.SilkS" user "Ref Des/Silkscreen Top")
		(7 "B.SilkS" user "Ref Des/Silkscreen Bottom")
		(1 "F.Mask" user "Board Geometry/Soldermask Top")
		(3 "B.Mask" user "Board Geometry/Soldermask Bottom")
		(17 "Dwgs.User" user "User.Drawings")
		(19 "Cmts.User" user "User.Comments")
		(21 "Eco1.User" user "User.Eco1")
		(23 "Eco2.User" user "User.Eco2")
		(25 "Edge.Cuts" user "Board Geometry/Outline")
		(27 "Margin" user)
		(31 "F.CrtYd" user "Package Geometry/Place Bound Top")
		(29 "B.CrtYd" user "Package Geometry/Place Bound Bottom")
		(35 "F.Fab" user "Ref Des/Assembly Top")
		(33 "B.Fab" user "Ref Des/Assembly Bottom")
	)
	(footprint ""
		(layer "B.Cu")
		(at 496.016534 -38.029896 90)
		(property "Reference" "R9F26"
			(at 0 0 90)
			(layer "B.SilkS")
			(hide yes)
			(effects
				(font
					(size 1.27 1.27)
				)
				(justify mirror)
			)
		)
		(property "Value" ""
			(at 0 0 90)
			(layer "B.Fab")
			(effects
				(font
					(size 1.27 1.27)
				)
				(justify mirror)
			)
		)
		(duplicate_pad_numbers_are_jumpers no)
		(fp_poly
			(pts
				(xy 0.2794 -0.1016) (xy -0.2794 -0.1016) (xy -0.2794 0.9906) (xy 0.2794 0.9906)
			)
			(stroke
				(width 0)
				(type default)
			)
			(fill no)
			(layer "B.CrtYd")
		)
		(fp_line
			(start 0.2794 -0.1016)
			(end 0.2794 0.9906)
			(stroke
				(width 0.1)
				(type default)
			)
			(layer "B.Fab")
		)
		(fp_line
			(start -0.2794 -0.1016)
			(end 0.2794 -0.1016)
			(stroke
				(width 0.1)
				(type default)
			)
			(layer "B.Fab")
		)
		(fp_line
			(start 0.2794 0.9906)
			(end -0.2794 0.9906)
			(stroke
				(width 0.1)
				(type default)
			)
			(layer "B.Fab")
		)
		(fp_line
			(start -0.2794 0.9906)
			(end -0.2794 -0.1016)
			(stroke
				(width 0.1)
				(type default)
			)
			(layer "B.Fab")
		)
		(pad "1" smd rect
			(at 0 0 270)
			(size 0.508 0.508)
			(layers "B.Cu" "B.Mask" "B.Paste")
			(net "SP2_BMC_CM_UART_TX")
		)
		(pad "2" smd rect
			(at 0 0.889 270)
			(size 0.508 0.508)
			(layers "B.Cu" "B.Mask" "B.Paste")
			(net "SPA_MID_DBG_TX")
		)
		(zone
			(layer "B.Cu")
			(hatch none 0.5)
			(connect_pads
				(clearance 0)
			)
			(min_thickness 0.25)
			(keepout
				(tracks allowed)
				(vias not_allowed)
				(pads allowed)
				(copperpour not_allowed)
				(footprints allowed)
			)
			(placement
				(enabled no)
				(sheetname "")
			)
			(fill
				(thermal_gap 0.5)
				(thermal_bridge_width 0.5)
				(island_removal_mode 0)
			)
			(polygon
				(pts
					(xy 496.270534 -38.283896) (xy 496.270534 -37.775896) (xy 496.651534 -37.775896) (xy 496.651534 -38.283896)
				)
			)
		)
		(zone
			(layer "B.Cu")
			(hatch none 0.5)
			(connect_pads
				(clearance 0)
			)
			(min_thickness 0.25)
			(keepout
				(tracks not_allowed)
				(vias allowed)
				(pads allowed)
				(copperpour not_allowed)
				(footprints allowed)
			)
			(placement
				(enabled no)
				(sheetname "")
			)
			(fill
				(thermal_gap 0.5)
				(thermal_bridge_width 0.5)
				(island_removal_mode 0)
			)
			(polygon
				(pts
					(xy 496.651534 -38.283896) (xy 496.651534 -37.775896) (xy 496.270534 -37.775896) (xy 496.270534 -38.283896)
				)
			)
		)
	)
	(footprint ""
		(layer "B.Cu")
		(at 257.8862 -149.7838 -90)
		(property "Reference" "C5G63"
			(at -1.14681 0.76708 0)
			(unlocked yes)
			(layer "B.SilkS")
			(effects
				(font
					(size 0.7874 0.5842)
					(thickness 0.1524)
				)
				(justify mirror)
			)
		)
		(property "Value" ""
			(at 0 0 90)
			(layer "B.Fab")
			(effects
				(font
					(size 1.27 1.27)
				)
				(justify mirror)
			)
		)
		(duplicate_pad_numbers_are_jumpers no)
		(fp_rect
			(start -0.4953 -0.2032)
			(end 0.4953 1.6002)
			(stroke
				(width 0)
				(type default)
			)
			(fill no)
			(layer "B.CrtYd")
		)
		(fp_line
			(start -0.4953 1.6002)
			(end 0.4953 1.6002)
			(stroke
				(width 0.1)
				(type default)
			)
			(layer "B.Fab")
		)
		(fp_line
			(start 0.4953 1.6002)
			(end 0.4953 -0.2032)
			(stroke
				(width 0.1)
				(type default)
			)
			(layer "B.Fab")
		)
		(fp_line
			(start -0.4953 -0.2032)
			(end -0.4953 1.6002)
			(stroke
				(width 0.1)
				(type default)
			)
			(layer "B.Fab")
		)
		(fp_line
			(start 0.4953 -0.2032)
			(end -0.4953 -0.2032)
			(stroke
				(width 0.1)
				(type default)
			)
			(layer "B.Fab")
		)
		(pad "1" smd rect
			(at 0 0 90)
			(size 0.762 0.889)
			(layers "B.Cu" "B.Mask" "B.Paste")
			(net "PVDDQ_DEF")
		)
		(pad "2" smd rect
			(at 0 1.397 90)
			(size 0.762 0.889)
			(layers "B.Cu" "B.Mask" "B.Paste")
			(net "GND")
		)
		(zone
			(layer "B.Cu")
			(hatch none 0.5)
			(connect_pads
				(clearance 0)
			)
			(min_thickness 0.25)
			(keepout
				(tracks not_allowed)
				(vias allowed)
				(pads allowed)
				(copperpour not_allowed)
				(footprints allowed)
			)
			(placement
				(enabled no)
				(sheetname "")
			)
			(fill
				(thermal_gap 0.5)
				(thermal_bridge_width 0.5)
				(island_removal_mode 0)
			)
			(polygon
				(pts
					(xy 257.4417 -150.1648) (xy 256.9337 -150.1648) (xy 256.9337 -149.4028) (xy 257.4417 -149.4028)
				)
			)
		)
	)
	(footprint ""
		(layer "B.Cu")
		(at 448.31 -147.066 180)
		(property "Reference" "C25W98"
			(at 0.8382 -0.67818 180)
			(unlocked yes)
			(layer "B.SilkS")
			(effects
				(font
					(size 0.4064 0.254)
					(thickness 0.1524)
				)
				(justify left mirror)
			)
		)
		(property "Value" ""
			(at 0 0 0)
			(layer "B.Fab")
			(effects
				(font
					(size 1.27 1.27)
				)
				(justify mirror)
			)
		)
		(duplicate_pad_numbers_are_jumpers no)
		(fp_poly
			(pts
				(xy -0.3048 -0.1016) (xy -0.3048 0.9906) (xy 0.3048 0.9906) (xy 0.3048 -0.1016)
			)
			(stroke
				(width 0)
				(type default)
			)
			(fill no)
			(layer "B.CrtYd")
		)
		(fp_line
			(start 0.3048 0.9906)
			(end -0.3048 0.9906)
			(stroke
				(width 0.1)
				(type default)
			)
			(layer "B.Fab")
		)
		(fp_line
			(start 0.3048 -0.1016)
			(end 0.3048 0.9906)
			(stroke
				(width 0.1)
				(type default)
			)
			(layer "B.Fab")
		)
		(fp_line
			(start -0.3048 0.9906)
			(end -0.3048 -0.1016)
			(stroke
				(width 0.1)
				(type default)
			)
			(layer "B.Fab")
		)
		(fp_line
			(start -0.3048 -0.1016)
			(end 0.3048 -0.1016)
			(stroke
				(width 0.1)
				(type default)
			)
			(layer "B.Fab")
		)
		(pad "1" smd rect
			(at 0 0)
			(size 0.508 0.508)
			(layers "B.Cu" "B.Mask" "B.Paste")
			(net "P3V3_STBY")
		)
		(pad "2" smd rect
			(at 0 0.889)
			(size 0.508 0.508)
			(layers "B.Cu" "B.Mask" "B.Paste")
			(net "GND")
		)
		(zone
			(layer "B.Cu")
			(hatch none 0.5)
			(connect_pads
				(clearance 0)
			)
			(min_thickness 0.25)
			(keepout
				(tracks not_allowed)
				(vias allowed)
				(pads allowed)
				(copperpour not_allowed)
				(footprints allowed)
			)
			(placement
				(enabled no)
				(sheetname "")
			)
			(fill
				(thermal_gap 0.5)
				(thermal_bridge_width 0.5)
				(island_removal_mode 0)
			)
			(polygon
				(pts
					(xy 448.056 -147.701) (xy 448.564 -147.701) (xy 448.564 -147.32) (xy 448.056 -147.32)
				)
			)
		)
		(zone
			(layer "B.Cu")
			(hatch none 0.5)
			(connect_pads
				(clearance 0)
			)
			(min_thickness 0.25)
			(keepout
				(tracks allowed)
				(vias not_allowed)
				(pads allowed)
				(copperpour not_allowed)
				(footprints allowed)
			)
			(placement
				(enabled no)
				(sheetname "")
			)
			(fill
				(thermal_gap 0.5)
				(thermal_bridge_width 0.5)
				(island_removal_mode 0)
			)
			(polygon
				(pts
					(xy 448.056 -147.32) (xy 448.564 -147.32) (xy 448.564 -147.701) (xy 448.056 -147.701)
				)
			)
		)
	)
)
